(kicad_pcb
	(version 20240108)
	(generator "pcbnew")
	(generator_version "8.0")
	(general
		(thickness 1.62)
		(legacy_teardrops no)
	)
	(paper "A4")
	(title_block
		(title "Jetson Orin Baseboard")
		(date "2025-03-12")
		(rev "1.3.4")
		(company "Antmicro Ltd")
		(comment 1 "www.antmicro.com")
		(comment 9 "footprints 341-345 of 677")
	)
	(layers
		(0 "F.Cu" signal)
		(1 "In1.Cu" signal)
		(2 "In2.Cu" signal)
		(3 "In3.Cu" signal)
		(4 "In4.Cu" jumper)
		(5 "In5.Cu" signal)
		(6 "In6.Cu" signal)
		(31 "B.Cu" signal)
		(32 "B.Adhes" user "B.Adhesive")
		(33 "F.Adhes" user "F.Adhesive")
		(34 "B.Paste" user)
		(35 "F.Paste" user)
		(36 "B.SilkS" user "B.Silkscreen")
		(37 "F.SilkS" user "F.Silkscreen")
		(38 "B.Mask" user)
		(39 "F.Mask" user)
		(40 "Dwgs.User" user "User.Drawings")
		(41 "Cmts.User" user "User.Comments")
		(42 "Eco1.User" user "User.Eco1")
		(43 "Eco2.User" user "User.Eco2")
		(44 "Edge.Cuts" user)
		(45 "Margin" user)
		(46 "B.CrtYd" user "B.Courtyard")
		(47 "F.CrtYd" user "F.Courtyard")
		(48 "B.Fab" user)
		(49 "F.Fab" user)
	)
	(footprint "antmicro-footprints:C_0402_1005Metric"
		(layer "B.Cu")
		(at 100.485 75.25)
		(descr "Capacitor SMD 0402")
		(tags "capacitor SMD 0402")
		(property "Reference" "C99"
			(at 1.215 1.34 180)
			(layer "B.SilkS")
			(effects
				(font
					(size 0.7 0.7)
					(thickness 0.15)
				)
				(justify left bottom mirror)
			)
		)
		(property "Value" "C_1u_0402"
			(at 0 -1.4 180)
			(layer "B.Fab")
			(effects
				(font
					(size 0.7 0.7)
					(thickness 0.15)
				)
				(justify left bottom mirror)
			)
		)
		(property "Footprint" "antmicro-footprints:C_0402_1005Metric"
			(at 0 0 0)
			(layer "F.Fab")
			(hide yes)
			(effects
				(font
					(size 1.27 1.27)
					(thickness 0.15)
				)
			)
		)
		(property "Datasheet" "https://product.tdk.com/en/search/capacitor/ceramic/mlcc/info?part_no=C1005X6S1A105K050BC"
			(at 0 0 0)
			(layer "F.Fab")
			(hide yes)
			(effects
				(font
					(size 1.27 1.27)
					(thickness 0.15)
				)
			)
		)
		(property "Author" "Antmicro"
			(at 0 0 0)
			(layer "B.Fab")
			(hide yes)
			(effects
				(font
					(size 1 1)
					(thickness 0.15)
				)
				(justify mirror)
			)
		)
		(property "Dielectric" ""
			(at 0 0 0)
			(layer "B.Fab")
			(hide yes)
			(effects
				(font
					(size 1 1)
					(thickness 0.15)
				)
				(justify mirror)
			)
		)
		(property "License" "Apache-2.0"
			(at 0 0 0)
			(layer "B.Fab")
			(hide yes)
			(effects
				(font
					(size 1 1)
					(thickness 0.15)
				)
				(justify mirror)
			)
		)
		(property "MPN" "C1005X6S1A105K050BC"
			(at 0 0 0)
			(layer "B.Fab")
			(hide yes)
			(effects
				(font
					(size 1 1)
					(thickness 0.15)
				)
				(justify mirror)
			)
		)
		(property "Manufacturer" "TDK"
			(at 0 0 0)
			(layer "B.Fab")
			(hide yes)
			(effects
				(font
					(size 1 1)
					(thickness 0.15)
				)
				(justify mirror)
			)
		)
		(property "Val" "1u"
			(at 0 0 0)
			(layer "B.Fab")
			(hide yes)
			(effects
				(font
					(size 1 1)
					(thickness 0.15)
				)
				(justify mirror)
			)
		)
		(property "Voltage" ""
			(at 0 0 0)
			(layer "B.Fab")
			(hide yes)
			(effects
				(font
					(size 1 1)
					(thickness 0.15)
				)
				(justify mirror)
			)
		)
		(sheetname "CSI")
		(sheetfile "csi.kicad_sch")
		(attr smd)
		(fp_rect
			(start -0.925 0.47)
			(end 0.925 -0.47)
			(stroke
				(width 0.05)
				(type default)
			)
			(fill none)
			(layer "B.CrtYd")
		)
		(fp_line
			(start -0.494 -0.248)
			(end 0.504 -0.248)
			(stroke
				(width 0.15)
				(type solid)
			)
			(layer "B.Fab")
		)
		(fp_line
			(start -0.494 0.25)
			(end -0.494 -0.248)
			(stroke
				(width 0.15)
				(type solid)
			)
			(layer "B.Fab")
		)
		(fp_line
			(start 0.504 -0.248)
			(end 0.504 0.25)
			(stroke
				(width 0.15)
				(type solid)
			)
			(layer "B.Fab")
		)
		(fp_line
			(start 0.504 0.25)
			(end -0.494 0.25)
			(stroke
				(width 0.15)
				(type solid)
			)
			(layer "B.Fab")
		)
		(fp_text user "Author: Antmicro"
			(at -0.932 -4.17 180)
			(layer "B.Fab")
			(hide yes)
			(effects
				(font
					(size 0.7 0.7)
					(thickness 0.15)
				)
				(justify left bottom mirror)
			)
		)
		(fp_text user "License: Apache-2.0"
			(at -0.932 -5.17 180)
			(layer "B.Fab")
			(hide yes)
			(effects
				(font
					(size 0.7 0.7)
					(thickness 0.15)
				)
				(justify left bottom mirror)
			)
		)
		(fp_text user "${REFERENCE}"
			(at -0.932 -3.168 180)
			(layer "B.Fab")
			(hide yes)
			(effects
				(font
					(size 0.7 0.7)
					(thickness 0.15)
				)
				(justify left bottom mirror)
			)
		)
		(pad "1" smd roundrect
			(at -0.48 0)
			(size 0.59 0.64)
			(layers "B.Cu" "B.Paste" "B.Mask")
			(roundrect_rratio 0.25)
			(net 1 "GND")
			(pintype "passive")
		)
		(pad "2" smd roundrect
			(at 0.48 0)
			(size 0.59 0.64)
			(layers "B.Cu" "B.Paste" "B.Mask")
			(roundrect_rratio 0.25)
			(net 111 "/CSI/CSIB_5V")
			(pintype "passive")
		)
	)
	(footprint "antmicro-footprints:R_0402_1005Metric"
		(layer "B.Cu")
		(at 55.125 87.45)
		(descr "Resistor SMD 0402")
		(tags "resistor SMD 0402")
		(property "Reference" "R149"
			(at -1.235 2.545 0)
			(layer "B.SilkS")
			(effects
				(font
					(size 0.7 0.7)
					(thickness 0.15)
				)
				(justify right top mirror)
			)
		)
		(property "Value" "R_10k_0402"
			(at 0 -1.4 0)
			(layer "B.Fab")
			(effects
				(font
					(size 0.7 0.7)
					(thickness 0.15)
				)
				(justify right top mirror)
			)
		)
		(property "Footprint" "antmicro-footprints:R_0402_1005Metric"
			(at 0 0 0)
			(layer "F.Fab")
			(hide yes)
			(effects
				(font
					(size 1.27 1.27)
					(thickness 0.15)
				)
			)
		)
		(property "Datasheet" "https://www.bourns.com/docs/product-datasheets/cr.pdf"
			(at 0 0 0)
			(layer "F.Fab")
			(hide yes)
			(effects
				(font
					(size 1.27 1.27)
					(thickness 0.15)
				)
			)
		)
		(property "Author" "Antmicro"
			(at -32.575 144.225 90)
			(layer "B.Fab")
			(hide yes)
			(effects
				(font
					(size 1 1)
					(thickness 0.15)
				)
				(justify mirror)
			)
		)
		(property "License" "Apache-2.0"
			(at -32.575 144.225 90)
			(layer "B.Fab")
			(hide yes)
			(effects
				(font
					(size 1 1)
					(thickness 0.15)
				)
				(justify mirror)
			)
		)
		(property "MPN" "CR0402-FX-1002GLF"
			(at -32.575 144.225 90)
			(layer "B.Fab")
			(hide yes)
			(effects
				(font
					(size 1 1)
					(thickness 0.15)
				)
				(justify mirror)
			)
		)
		(property "Manufacturer" "Bourns"
			(at -32.575 144.225 90)
			(layer "B.Fab")
			(hide yes)
			(effects
				(font
					(size 1 1)
					(thickness 0.15)
				)
				(justify mirror)
			)
		)
		(property "Tolerance" "1%"
			(at -32.575 144.225 90)
			(layer "B.Fab")
			(hide yes)
			(effects
				(font
					(size 1 1)
					(thickness 0.15)
				)
				(justify mirror)
			)
		)
		(property "Val" "10k"
			(at -32.575 144.225 90)
			(layer "B.Fab")
			(hide yes)
			(effects
				(font
					(size 1 1)
					(thickness 0.15)
				)
				(justify mirror)
			)
		)
		(sheetname "Ethernet")
		(sheetfile "ethernet.kicad_sch")
		(attr smd exclude_from_pos_files exclude_from_bom dnp)
		(fp_rect
			(start -0.925 0.47)
			(end 0.925 -0.47)
			(stroke
				(width 0.05)
				(type default)
			)
			(fill none)
			(layer "B.CrtYd")
		)
		(fp_rect
			(start -0.5 0.25)
			(end 0.5 -0.25)
			(stroke
				(width 0.15)
				(type solid)
			)
			(fill none)
			(layer "B.Fab")
		)
		(fp_text user "Author: Antmicro"
			(at -0.95 -4.169 0)
			(layer "B.Fab")
			(hide yes)
			(effects
				(font
					(size 0.7 0.7)
					(thickness 0.15)
				)
				(justify right top mirror)
			)
		)
		(fp_text user "License: Apache-2.0"
			(at -0.95 -5.169 0)
			(layer "B.Fab")
			(hide yes)
			(effects
				(font
					(size 0.7 0.7)
					(thickness 0.15)
				)
				(justify right top mirror)
			)
		)
		(fp_text user "${REFERENCE}"
			(at -0.95 -3.168 0)
			(layer "B.Fab")
			(hide yes)
			(effects
				(font
					(size 0.7 0.7)
					(thickness 0.15)
				)
				(justify right top mirror)
			)
		)
		(pad "1" smd roundrect
			(at -0.48 0)
			(size 0.59 0.64)
			(layers "B.Cu" "B.Paste" "B.Mask")
			(roundrect_rratio 0.25)
			(net 572 "/Ethernet/TPH")
			(pintype "passive")
		)
		(pad "2" smd roundrect
			(at 0.48 0)
			(size 0.59 0.64)
			(layers "B.Cu" "B.Paste" "B.Mask")
			(roundrect_rratio 0.25)
			(net 105 "/Ethernet/VDD")
			(pintype "passive")
		)
	)
	(footprint "antmicro-footprints:C_0603_1608Metric"
		(layer "B.Cu")
		(at 38.29 113.14 90)
		(descr "Capacitor SMD 0603")
		(tags "capacitor 0603")
		(property "Reference" "C77"
			(at -1.01 1.51 90)
			(layer "B.SilkS")
			(effects
				(font
					(size 0.7 0.7)
					(thickness 0.15)
				)
				(justify right bottom mirror)
			)
		)
		(property "Value" "C_10n_0603"
			(at -2.055717 -1.963152 90)
			(layer "B.Fab")
			(effects
				(font
					(size 0.7 0.7)
					(thickness 0.15)
				)
				(justify right bottom mirror)
			)
		)
		(property "Footprint" "antmicro-footprints:C_0603_1608Metric"
			(at 0 0 90)
			(layer "F.Fab")
			(hide yes)
			(effects
				(font
					(size 1.27 1.27)
					(thickness 0.15)
				)
			)
		)
		(property "Datasheet" "https://spicat.kyocera-avx.com/product/mlcc/chartview/06031C103JAT2A/"
			(at 0 0 90)
			(layer "F.Fab")
			(hide yes)
			(effects
				(font
					(size 1.27 1.27)
					(thickness 0.15)
				)
			)
		)
		(property "Author" "Antmicro"
			(at 151.43 74.85 0)
			(layer "B.Fab")
			(hide yes)
			(effects
				(font
					(size 1 1)
					(thickness 0.15)
				)
				(justify mirror)
			)
		)
		(property "Dielectric" ""
			(at 151.43 74.85 0)
			(layer "B.Fab")
			(hide yes)
			(effects
				(font
					(size 1 1)
					(thickness 0.15)
				)
				(justify mirror)
			)
		)
		(property "License" "Apache-2.0"
			(at 151.43 74.85 0)
			(layer "B.Fab")
			(hide yes)
			(effects
				(font
					(size 1 1)
					(thickness 0.15)
				)
				(justify mirror)
			)
		)
		(property "MPN" "06031C103JAT2A"
			(at 151.43 74.85 0)
			(layer "B.Fab")
			(hide yes)
			(effects
				(font
					(size 1 1)
					(thickness 0.15)
				)
				(justify mirror)
			)
		)
		(property "Manufacturer" "AVX"
			(at 151.43 74.85 0)
			(layer "B.Fab")
			(hide yes)
			(effects
				(font
					(size 1 1)
					(thickness 0.15)
				)
				(justify mirror)
			)
		)
		(property "Val" "10n"
			(at 151.43 74.85 0)
			(layer "B.Fab")
			(hide yes)
			(effects
				(font
					(size 1 1)
					(thickness 0.15)
				)
				(justify mirror)
			)
		)
		(property "Voltage" ""
			(at 151.43 74.85 0)
			(layer "B.Fab")
			(hide yes)
			(effects
				(font
					(size 1 1)
					(thickness 0.15)
				)
				(justify mirror)
			)
		)
		(sheetname "Ethernet")
		(sheetfile "ethernet.kicad_sch")
		(attr smd)
		(fp_line
			(start 0.15 -0.4)
			(end -0.15 -0.4)
			(stroke
				(width 0.15)
				(type solid)
			)
			(layer "B.SilkS")
		)
		(fp_line
			(start 0.15 0.4)
			(end -0.15 0.4)
			(stroke
				(width 0.15)
				(type solid)
			)
			(layer "B.SilkS")
		)
		(fp_rect
			(start -1.25 0.65)
			(end 1.25 -0.65)
			(stroke
				(width 0.05)
				(type solid)
			)
			(fill none)
			(layer "B.CrtYd")
		)
		(fp_rect
			(start -0.8 0.4)
			(end 0.8 -0.4)
			(stroke
				(width 0.15)
				(type solid)
			)
			(fill none)
			(layer "B.Fab")
		)
		(fp_text user "License: Apache-2.0"
			(at -1.9 -4.947 90)
			(layer "B.Fab")
			(hide yes)
			(effects
				(font
					(size 0.7 0.7)
					(thickness 0.15)
				)
				(justify right bottom mirror)
			)
		)
		(fp_text user "${REFERENCE}"
			(at -1.9 -3.947 90)
			(layer "B.Fab")
			(hide yes)
			(effects
				(font
					(size 0.7 0.7)
					(thickness 0.15)
				)
				(justify right bottom mirror)
			)
		)
		(fp_text user "Author: Antmicro"
			(at -1.9 -5.947 90)
			(layer "B.Fab")
			(hide yes)
			(effects
				(font
					(size 0.7 0.7)
					(thickness 0.15)
				)
				(justify right bottom mirror)
			)
		)
		(pad "1" smd roundrect
			(at -0.7 0 90)
			(size 0.8 1)
			(layers "B.Cu" "B.Paste" "B.Mask")
			(roundrect_rratio 0.2)
			(net 1 "GND")
			(pintype "passive")
		)
		(pad "2" smd roundrect
			(at 0.7 0 90)
			(size 0.8 1)
			(layers "B.Cu" "B.Paste" "B.Mask")
			(roundrect_rratio 0.2)
			(net 136 "Net-(J6-P4)")
			(pintype "passive")
		)
	)
	(footprint "antmicro-footprints:R_0402_1005Metric"
		(layer "B.Cu")
		(at 54.3 78.59 90)
		(descr "Resistor SMD 0402")
		(tags "resistor SMD 0402")
		(property "Reference" "R275"
			(at -10.51 21 -90)
			(layer "B.SilkS")
			(effects
				(font
					(size 0.7 0.7)
					(thickness 0.15)
				)
				(justify right top mirror)
			)
		)
		(property "Value" "R_10k_0402"
			(at -1.011843 -1.772047 90)
			(layer "B.Fab")
			(effects
				(font
					(size 0.7 0.7)
					(thickness 0.15)
				)
				(justify right top mirror)
			)
		)
		(property "Footprint" "antmicro-footprints:R_0402_1005Metric"
			(at 0 0 90)
			(layer "B.Fab")
			(hide yes)
			(effects
				(font
					(size 1.27 1.27)
					(thickness 0.15)
				)
				(justify mirror)
			)
		)
		(property "Datasheet" "https://www.bourns.com/docs/product-datasheets/cr.pdf"
			(at 0 0 90)
			(layer "B.Fab")
			(hide yes)
			(effects
				(font
					(size 1.27 1.27)
					(thickness 0.15)
				)
				(justify mirror)
			)
		)
		(property "Manufacturer" "Bourns"
			(at 0 0 -90)
			(unlocked yes)
			(layer "B.Fab")
			(hide yes)
			(effects
				(font
					(size 1 1)
					(thickness 0.15)
				)
				(justify mirror)
			)
		)
		(property "MPN" "CR0402-FX-1002GLF"
			(at 0 0 -90)
			(unlocked yes)
			(layer "B.Fab")
			(hide yes)
			(effects
				(font
					(size 1 1)
					(thickness 0.15)
				)
				(justify mirror)
			)
		)
		(property "Val" "10k"
			(at 0 0 -90)
			(unlocked yes)
			(layer "B.Fab")
			(hide yes)
			(effects
				(font
					(size 1 1)
					(thickness 0.15)
				)
				(justify mirror)
			)
		)
		(property "License" "Apache-2.0"
			(at 0 0 -90)
			(unlocked yes)
			(layer "B.Fab")
			(hide yes)
			(effects
				(font
					(size 1 1)
					(thickness 0.15)
				)
				(justify mirror)
			)
		)
		(property "Author" "Antmicro"
			(at 0 0 -90)
			(unlocked yes)
			(layer "B.Fab")
			(hide yes)
			(effects
				(font
					(size 1 1)
					(thickness 0.15)
				)
				(justify mirror)
			)
		)
		(property "Tolerance" "1%"
			(at 0 0 -90)
			(unlocked yes)
			(layer "B.Fab")
			(hide yes)
			(effects
				(font
					(size 1 1)
					(thickness 0.15)
				)
				(justify mirror)
			)
		)
		(sheetname "Supply")
		(sheetfile "supply.kicad_sch")
		(attr smd)
		(fp_rect
			(start -0.925 0.47)
			(end 0.925 -0.47)
			(stroke
				(width 0.05)
				(type default)
			)
			(fill none)
			(layer "B.CrtYd")
		)
		(fp_rect
			(start -0.5 0.25)
			(end 0.5 -0.25)
			(stroke
				(width 0.15)
				(type solid)
			)
			(fill none)
			(layer "B.Fab")
		)
		(fp_text user "${REFERENCE}"
			(at -0.95 -3.168 90)
			(layer "B.Fab")
			(hide yes)
			(effects
				(font
					(size 0.7 0.7)
					(thickness 0.15)
				)
				(justify right top mirror)
			)
		)
		(fp_text user "License: Apache-2.0"
			(at -0.95 -5.169 90)
			(layer "B.Fab")
			(hide yes)
			(effects
				(font
					(size 0.7 0.7)
					(thickness 0.15)
				)
				(justify right top mirror)
			)
		)
		(fp_text user "Author: Antmicro"
			(at -0.95 -4.169 90)
			(layer "B.Fab")
			(hide yes)
			(effects
				(font
					(size 0.7 0.7)
					(thickness 0.15)
				)
				(justify right top mirror)
			)
		)
		(pad "1" smd roundrect
			(at -0.48 0 90)
			(size 0.59 0.64)
			(layers "B.Cu" "B.Paste" "B.Mask")
			(roundrect_rratio 0.25)
			(net 789 "MODULE_ID")
			(pintype "passive")
		)
		(pad "2" smd roundrect
			(at 0.48 0 90)
			(size 0.59 0.64)
			(layers "B.Cu" "B.Paste" "B.Mask")
			(roundrect_rratio 0.25)
			(net 787 "+5V_SoM")
			(pintype "passive")
		)
	)
	(footprint "antmicro-footprints:R_0402_1005Metric"
		(layer "B.Cu")
		(at 84.4 101.3 90)
		(descr "Resistor SMD 0402")
		(tags "resistor SMD 0402")
		(property "Reference" "R205"
			(at 1.65 -0.4 -90)
			(layer "B.SilkS")
			(effects
				(font
					(size 0.7 0.7)
					(thickness 0.15)
				)
				(justify left bottom mirror)
			)
		)
		(property "Value" "R_100k_0402"
			(at 0 -1.4 -90)
			(layer "B.Fab")
			(effects
				(font
					(size 0.7 0.7)
					(thickness 0.15)
				)
				(justify left bottom mirror)
			)
		)
		(property "Footprint" "antmicro-footprints:R_0402_1005Metric"
			(at 0 0 90)
			(layer "F.Fab")
			(hide yes)
			(effects
				(font
					(size 1.27 1.27)
					(thickness 0.15)
				)
			)
		)
		(property "Datasheet" "https://www.bourns.com/docs/product-datasheets/cr.pdf"
			(at 0 0 90)
			(layer "F.Fab")
			(hide yes)
			(effects
				(font
					(size 1.27 1.27)
					(thickness 0.15)
				)
			)
		)
		(property "Author" "Antmicro"
			(at 185.7 16.9 0)
			(layer "B.Fab")
			(hide yes)
			(effects
				(font
					(size 1 1)
					(thickness 0.15)
				)
				(justify mirror)
			)
		)
		(property "License" "Apache-2.0"
			(at 185.7 16.9 0)
			(layer "B.Fab")
			(hide yes)
			(effects
				(font
					(size 1 1)
					(thickness 0.15)
				)
				(justify mirror)
			)
		)
		(property "MPN" "CR0402-FX-1003GLF"
			(at 185.7 16.9 0)
			(layer "B.Fab")
			(hide yes)
			(effects
				(font
					(size 1 1)
					(thickness 0.15)
				)
				(justify mirror)
			)
		)
		(property "Manufacturer" "Bourns"
			(at 185.7 16.9 0)
			(layer "B.Fab")
			(hide yes)
			(effects
				(font
					(size 1 1)
					(thickness 0.15)
				)
				(justify mirror)
			)
		)
		(property "Tolerance" "1%"
			(at 185.7 16.9 0)
			(layer "B.Fab")
			(hide yes)
			(effects
				(font
					(size 1 1)
					(thickness 0.15)
				)
				(justify mirror)
			)
		)
		(property "Val" "100k"
			(at 185.7 16.9 0)
			(layer "B.Fab")
			(hide yes)
			(effects
				(font
					(size 1 1)
					(thickness 0.15)
				)
				(justify mirror)
			)
		)
		(sheetname "USB Debug, DP")
		(sheetfile "usb.kicad_sch")
		(attr smd)
		(fp_rect
			(start -0.925 0.47)
			(end 0.925 -0.47)
			(stroke
				(width 0.05)
				(type default)
			)
			(fill none)
			(layer "B.CrtYd")
		)
		(fp_rect
			(start -0.5 0.25)
			(end 0.5 -0.25)
			(stroke
				(width 0.15)
				(type solid)
			)
			(fill none)
			(layer "B.Fab")
		)
		(fp_text user "License: Apache-2.0"
			(at -0.95 -5.169 -90)
			(layer "B.Fab")
			(hide yes)
			(effects
				(font
					(size 0.7 0.7)
					(thickness 0.15)
				)
				(justify left bottom mirror)
			)
		)
		(fp_text user "${REFERENCE}"
			(at -0.95 -3.168 -90)
			(layer "B.Fab")
			(hide yes)
			(effects
				(font
					(size 0.7 0.7)
					(thickness 0.15)
				)
				(justify left bottom mirror)
			)
		)
		(fp_text user "Author: Antmicro"
			(at -0.95 -4.169 -90)
			(layer "B.Fab")
			(hide yes)
			(effects
				(font
					(size 0.7 0.7)
					(thickness 0.15)
				)
				(justify left bottom mirror)
			)
		)
		(pad "1" smd roundrect
			(at -0.48 0 90)
			(size 0.59 0.64)
			(layers "B.Cu" "B.Paste" "B.Mask")
			(roundrect_rratio 0.25)
			(net 36 "DP1_AUX_P")
			(pintype "passive")
		)
		(pad "2" smd roundrect
			(at 0.48 0 90)
			(size 0.59 0.64)
			(layers "B.Cu" "B.Paste" "B.Mask")
			(roundrect_rratio 0.25)
			(net 1 "GND")
			(pintype "passive")
		)
	)
)
